(kicad_pcb
	(version 20260206)
	(generator "pcbnew")
	(generator_version "10.0")
	(general
		(thickness 1.6)
		(legacy_teardrops no)
	)
	(paper "A4")
	(title_block
		(title "Wiwynn_Tioga_Pass_MB.brd")
		(comment 1 "Tioga Pass / footprint 1664 of 4770 (U7C1), pads 463-577 of 1310")
	)
	(layers
		(0 "F.Cu" signal "TOP")
		(4 "In1.Cu" signal "L2GND")
		(6 "In2.Cu" signal "L3")
		(8 "In3.Cu" signal "L4GND")
		(10 "In4.Cu" signal "L5")
		(12 "In5.Cu" signal "L6GND")
		(14 "In6.Cu" signal "L7VCC")
		(16 "In7.Cu" signal "L8VCC")
		(18 "In8.Cu" signal "L9GND")
		(20 "In9.Cu" signal "L10")
		(22 "In10.Cu" signal "L11GND")
		(24 "In11.Cu" signal "L12")
		(26 "In12.Cu" signal "L13GND")
		(2 "B.Cu" signal "BOTTOM")
		(9 "F.Adhes" user "F.Adhesive")
		(11 "B.Adhes" user "B.Adhesive")
		(13 "F.Paste" user "Package Geometry/Pastemask Top")
		(15 "B.Paste" user "Package Geometry/Pastemask Bottom")
		(5 "F.SilkS" user "Ref Des/Silkscreen Top")
		(7 "B.SilkS" user "Ref Des/Silkscreen Bottom")
		(1 "F.Mask" user "Board Geometry/Soldermask Top")
		(3 "B.Mask" user "Board Geometry/Soldermask Bottom")
		(17 "Dwgs.User" user "User.Drawings")
		(19 "Cmts.User" user "User.Comments")
		(21 "Eco1.User" user "User.Eco1")
		(23 "Eco2.User" user "User.Eco2")
		(25 "Edge.Cuts" user "Board Geometry/Outline")
		(27 "Margin" user)
		(31 "F.CrtYd" user "Package Geometry/Place Bound Top")
		(29 "B.CrtYd" user "Package Geometry/Place Bound Bottom")
		(35 "F.Fab" user "Ref Des/Assembly Top")
		(33 "B.Fab" user "Ref Des/Assembly Bottom")
	)
	(footprint ""
		(layer "F.Cu")
		(at 387.985 -109.855 90)
		(property "Reference" "U7C1"
			(at 17.75333 -13.335 0)
			(unlocked yes)
			(layer "F.SilkS")
			(effects
				(font
					(size 0.7874 0.5842)
					(thickness 0.1524)
				)
				(justify left)
			)
		)
		(property "Value" ""
			(at 0 0 90)
			(layer "F.Fab")
			(effects
				(font
					(size 1.27 1.27)
				)
			)
		)
		(duplicate_pad_numbers_are_jumpers no)
		(pad "B23" smd circle
			(at -6.500114 -12.895072 90)
			(size 0.3048 0.3048)
			(layers "F.Cu" "F.Mask" "F.Paste")
			(net "CLK_100M_MEZZ3_DN")
		)
		(pad "B25" smd circle
			(at -5.500116 -12.895072 90)
			(size 0.3048 0.3048)
			(layers "F.Cu" "F.Mask" "F.Paste")
			(net "GND")
		)
		(pad "B27" smd circle
			(at -4.500118 -12.895072 90)
			(size 0.3048 0.3048)
			(layers "F.Cu" "F.Mask" "F.Paste")
			(net "GND")
		)
		(pad "B29" smd circle
			(at -3.50012 -12.895072 90)
			(size 0.3048 0.3048)
			(layers "F.Cu" "F.Mask" "F.Paste")
			(net "CLK_100M_BMC_PE_DN")
		)
		(pad "B31" smd circle
			(at -2.500122 -12.895072 90)
			(size 0.3048 0.3048)
			(layers "F.Cu" "F.Mask" "F.Paste")
			(net "CLK_100M_MEZZ1_DP")
		)
		(pad "B33" smd circle
			(at -1.500124 -12.895072 90)
			(size 0.3048 0.3048)
			(layers "F.Cu" "F.Mask" "F.Paste")
			(net "CLK_100M_PCH_SLOTX24_S4_DP")
		)
		(pad "B35" smd circle
			(at -0.500126 -12.895072 90)
			(size 0.3048 0.3048)
			(layers "F.Cu" "F.Mask" "F.Paste")
			(net "XTAL_PCH_48M_IN")
		)
		(pad "B38" smd circle
			(at 0.500126 -12.895072 90)
			(size 0.3048 0.3048)
			(layers "F.Cu" "F.Mask" "F.Paste")
			(net "TP_CLK_100M_NSSCC1_DN")
		)
		(pad "B40" smd circle
			(at 1.500124 -12.895072 90)
			(size 0.3048 0.3048)
			(layers "F.Cu" "F.Mask" "F.Paste")
			(net "TP_CLK_100M_PLAT1_DN")
		)
		(pad "B42" smd circle
			(at 2.500122 -12.895072 90)
			(size 0.3048 0.3048)
			(layers "F.Cu" "F.Mask" "F.Paste")
			(net "DMI_CPU0_PCH_TX_C_DP<0>")
		)
		(pad "B44" smd circle
			(at 3.50012 -12.895072 90)
			(size 0.3048 0.3048)
			(layers "F.Cu" "F.Mask" "F.Paste")
			(net "DMI_CPU0_PCH_TX_C_DP<2>")
		)
		(pad "B47" smd circle
			(at 4.500118 -12.895072 90)
			(size 0.3048 0.3048)
			(layers "F.Cu" "F.Mask" "F.Paste")
			(net "GND")
		)
		(pad "B49" smd circle
			(at 5.500116 -12.895072 90)
			(size 0.3048 0.3048)
			(layers "F.Cu" "F.Mask" "F.Paste")
			(net "P3E_CPU0_PE1_PCH_TXP<1>")
		)
		(pad "B51" smd circle
			(at 6.500114 -12.895072 90)
			(size 0.3048 0.3048)
			(layers "F.Cu" "F.Mask" "F.Paste")
			(net "P3E_CPU0_PE1_PCH_TXP<3>")
		)
		(pad "B53" smd circle
			(at 7.500112 -12.895072 90)
			(size 0.3048 0.3048)
			(layers "F.Cu" "F.Mask" "F.Paste")
			(net "P3E_CPU0_PE1_PCH_TXP<5>")
		)
		(pad "B55" smd circle
			(at 8.50011 -12.895072 90)
			(size 0.3048 0.3048)
			(layers "F.Cu" "F.Mask" "F.Paste")
			(net "P3E_CPU0_PE1_PCH_TXP<7>")
		)
		(pad "B58" smd circle
			(at 9.500108 -12.895072 90)
			(size 0.3048 0.3048)
			(layers "F.Cu" "F.Mask" "F.Paste")
			(net "P3E_CPU0_PE1_PCH_C_TXN<9>")
		)
		(pad "B60" smd circle
			(at 10.500106 -12.895072 90)
			(size 0.3048 0.3048)
			(layers "F.Cu" "F.Mask" "F.Paste")
			(net "P3E_CPU0_PE1_PCH_C_TXP<11>")
		)
		(pad "B62" smd circle
			(at 11.500104 -12.895072 90)
			(size 0.3048 0.3048)
			(layers "F.Cu" "F.Mask" "F.Paste")
			(net "P3E_CPU0_PE1_PCH_C_TXN<13>")
		)
		(pad "B64" smd circle
			(at 12.500102 -12.895072 90)
			(size 0.3048 0.3048)
			(layers "F.Cu" "F.Mask" "F.Paste")
			(net "P3E_CPU0_PE1_PCH_C_TXN<15>")
		)
		(pad "BA2" smd circle
			(at -15.895066 4.500118 180)
			(size 0.3048 0.3048)
			(layers "F.Cu" "F.Mask" "F.Paste")
			(net "FM_BIOS_SMI_ACTIVE_N")
		)
		(pad "BA4" smd circle
			(at -15.064994 4.500118 180)
			(size 0.3048 0.3048)
			(layers "F.Cu" "F.Mask" "F.Paste")
			(net "SMB_VR_STBY_LVC3_SCL_R1")
		)
		(pad "BA9" smd circle
			(at -12.8778 4.70535)
			(size 0.381 0.381)
			(layers "F.Cu" "F.Mask" "F.Paste")
			(net "Net_469")
		)
		(pad "BA13" smd circle
			(at -11.16076 4.70535)
			(size 0.381 0.381)
			(layers "F.Cu" "F.Mask" "F.Paste")
			(net "FM_UARTSW_MSB_N")
		)
		(pad "BA17" smd circle
			(at -9.44372 4.70535)
			(size 0.381 0.381)
			(layers "F.Cu" "F.Mask" "F.Paste")
			(net "IRQ_FORCE_NM_THROTTLE_N")
		)
		(pad "BA20" smd circle
			(at -7.72668 4.70535)
			(size 0.381 0.381)
			(layers "F.Cu" "F.Mask" "F.Paste")
			(net "Net_473")
		)
		(pad "BA24" smd circle
			(at -6.00964 4.70535)
			(size 0.381 0.381)
			(layers "F.Cu" "F.Mask" "F.Paste")
			(net "P3V3_STBY")
		)
		(pad "BA26" smd circle
			(at -5.20065 4.55295 180)
			(size 0.381 0.381)
			(layers "F.Cu" "F.Mask" "F.Paste")
			(net "P3V3_STBY")
		)
		(pad "BA27" smd circle
			(at -4.40055 4.55295 180)
			(size 0.381 0.381)
			(layers "F.Cu" "F.Mask" "F.Paste")
			(net "P1V8_PCH_STBY")
		)
		(pad "BA29" smd circle
			(at -3.60045 4.55295 180)
			(size 0.381 0.381)
			(layers "F.Cu" "F.Mask" "F.Paste")
			(net "P1V8_PCH_STBY")
		)
		(pad "BA30" smd circle
			(at -2.80035 4.55295 180)
			(size 0.381 0.381)
			(layers "F.Cu" "F.Mask" "F.Paste")
			(net "P1V05_PCH_STBY")
		)
		(pad "BA32" smd circle
			(at -2.00025 4.55295 180)
			(size 0.381 0.381)
			(layers "F.Cu" "F.Mask" "F.Paste")
			(net "P1V05_PCH_STBY")
		)
		(pad "BA34" smd circle
			(at -1.20015 4.55295 180)
			(size 0.381 0.381)
			(layers "F.Cu" "F.Mask" "F.Paste")
			(net "P1V05_PCH_STBY")
		)
		(pad "BA36" smd circle
			(at -0.40005 4.55295 180)
			(size 0.381 0.381)
			(layers "F.Cu" "F.Mask" "F.Paste")
			(net "P1V05_PCH_STBY")
		)
		(pad "BA37" smd circle
			(at 0.40005 4.55295 180)
			(size 0.381 0.381)
			(layers "F.Cu" "F.Mask" "F.Paste")
			(net "P1V05_PCH_STBY")
		)
		(pad "BA39" smd circle
			(at 1.20015 4.55295 180)
			(size 0.381 0.381)
			(layers "F.Cu" "F.Mask" "F.Paste")
			(net "P1V05_PCH_STBY_KR_PLL")
		)
		(pad "BA41" smd circle
			(at 2.00025 4.55295 180)
			(size 0.381 0.381)
			(layers "F.Cu" "F.Mask" "F.Paste")
			(net "P1V05_PCH_STBY_KR_PLL")
		)
		(pad "BA43" smd circle
			(at 2.80035 4.55295 180)
			(size 0.381 0.381)
			(layers "F.Cu" "F.Mask" "F.Paste")
			(net "P3V3_STBY")
		)
		(pad "BA45" smd circle
			(at 3.60045 4.55295 180)
			(size 0.381 0.381)
			(layers "F.Cu" "F.Mask" "F.Paste")
			(net "P3V3_STBY")
		)
		(pad "BA46" smd circle
			(at 4.40055 4.55295 180)
			(size 0.381 0.381)
			(layers "F.Cu" "F.Mask" "F.Paste")
			(net "P3V3_STBY")
		)
		(pad "BA48" smd circle
			(at 5.20065 4.55295 180)
			(size 0.381 0.381)
			(layers "F.Cu" "F.Mask" "F.Paste")
			(net "P3V3_STBY")
		)
		(pad "BA50" smd circle
			(at 6.00964 4.70535)
			(size 0.381 0.381)
			(layers "F.Cu" "F.Mask" "F.Paste")
			(net "GND")
		)
		(pad "BA54" smd circle
			(at 7.72668 4.70535)
			(size 0.381 0.381)
			(layers "F.Cu" "F.Mask" "F.Paste")
			(net "GND")
		)
		(pad "BA58" smd circle
			(at 9.44372 4.70535)
			(size 0.381 0.381)
			(layers "F.Cu" "F.Mask" "F.Paste")
			(net "GND")
		)
		(pad "BA61" smd circle
			(at 11.16076 4.70535)
			(size 0.381 0.381)
			(layers "F.Cu" "F.Mask" "F.Paste")
			(net "SATA6G_S1_RX_DP")
		)
		(pad "BA65" smd circle
			(at 12.8778 4.70535)
			(size 0.381 0.381)
			(layers "F.Cu" "F.Mask" "F.Paste")
			(net "Net_134")
		)
		(pad "BA69" smd circle
			(at 15.064994 4.500118)
			(size 0.3048 0.3048)
			(layers "F.Cu" "F.Mask" "F.Paste")
			(net "P3E_PCH_RX_0_DP")
		)
		(pad "BA71" smd circle
			(at 15.895066 4.500118)
			(size 0.3048 0.3048)
			(layers "F.Cu" "F.Mask" "F.Paste")
			(net "P3E_PCH_RX_0_DN")
		)
		(pad "BB1" smd oval
			(at -16.310102 4.99999 180)
			(size 0.254 0.3302)
			(layers "F.Cu" "F.Mask" "F.Paste")
			(net "FM_FLASH_ATTACH_CFG_STRAP")
		)
		(pad "BB3" smd circle
			(at -15.48003 4.99999 180)
			(size 0.3048 0.3048)
			(layers "F.Cu" "F.Mask" "F.Paste")
			(net "PU_ADR_TIMER_HOLD_OFF_N")
		)
		(pad "BB5" smd circle
			(at -14.649958 4.99999 180)
			(size 0.3048 0.3048)
			(layers "F.Cu" "F.Mask" "F.Paste")
			(net "GND")
		)
		(pad "BB7" smd circle
			(at -13.73632 5.20065)
			(size 0.381 0.381)
			(layers "F.Cu" "F.Mask" "F.Paste")
			(net "GND")
		)
		(pad "BB11" smd circle
			(at -12.01928 5.20065)
			(size 0.381 0.381)
			(layers "F.Cu" "F.Mask" "F.Paste")
			(net "GND")
		)
		(pad "BB15" smd circle
			(at -10.30224 5.20065)
			(size 0.381 0.381)
			(layers "F.Cu" "F.Mask" "F.Paste")
			(net "GND")
		)
		(pad "BB18" smd circle
			(at -8.5852 5.20065)
			(size 0.381 0.381)
			(layers "F.Cu" "F.Mask" "F.Paste")
			(net "GND")
		)
		(pad "BB22" smd circle
			(at -6.86816 5.20065)
			(size 0.381 0.381)
			(layers "F.Cu" "F.Mask" "F.Paste")
			(net "GND")
		)
		(pad "BB26" smd circle
			(at -5.15112 5.201158)
			(size 0.381 0.381)
			(layers "F.Cu" "F.Mask" "F.Paste")
			(net "P3V3_STBY")
		)
		(pad "BB29" smd circle
			(at -3.43408 5.20065)
			(size 0.381 0.381)
			(layers "F.Cu" "F.Mask" "F.Paste")
			(net "A_KR0_RBIAS")
		)
		(pad "BB33" smd circle
			(at -1.71704 5.20065)
			(size 0.381 0.381)
			(layers "F.Cu" "F.Mask" "F.Paste")
			(net "P1V05_PCH_STBY")
		)
		(pad "BB37" smd circle
			(at 0 5.20065)
			(size 0.381 0.381)
			(layers "F.Cu" "F.Mask" "F.Paste")
			(net "P1V05_PCH_STBY")
		)
		(pad "BB40" smd circle
			(at 1.71704 5.20065)
			(size 0.381 0.381)
			(layers "F.Cu" "F.Mask" "F.Paste")
			(net "P1V05_PCH_STBY_KR_PLL")
		)
		(pad "BB44" smd circle
			(at 3.43408 5.20065)
			(size 0.381 0.381)
			(layers "F.Cu" "F.Mask" "F.Paste")
			(net "GND")
		)
		(pad "BB48" smd circle
			(at 5.15112 5.201158)
			(size 0.381 0.381)
			(layers "F.Cu" "F.Mask" "F.Paste")
			(net "GND")
		)
		(pad "BB52" smd circle
			(at 6.86816 5.20065)
			(size 0.381 0.381)
			(layers "F.Cu" "F.Mask" "F.Paste")
			(net "IRQ_BMC_PCH_NMI_STBY_N")
		)
		(pad "BB56" smd circle
			(at 8.5852 5.20065)
			(size 0.381 0.381)
			(layers "F.Cu" "F.Mask" "F.Paste")
			(net "A_PCIE_RCOMP_P")
		)
		(pad "BB59" smd circle
			(at 10.30224 5.20065)
			(size 0.381 0.381)
			(layers "F.Cu" "F.Mask" "F.Paste")
			(net "GND")
		)
		(pad "BB63" smd circle
			(at 12.01928 5.20065)
			(size 0.381 0.381)
			(layers "F.Cu" "F.Mask" "F.Paste")
			(net "SATA6G_S0_RX_DN")
		)
		(pad "BB66" smd circle
			(at 13.73632 5.20065)
			(size 0.381 0.381)
			(layers "F.Cu" "F.Mask" "F.Paste")
			(net "GND")
		)
		(pad "BB68" smd circle
			(at 14.649958 4.99999)
			(size 0.3048 0.3048)
			(layers "F.Cu" "F.Mask" "F.Paste")
			(net "GND")
		)
		(pad "BB70" smd circle
			(at 15.48003 4.99999)
			(size 0.3048 0.3048)
			(layers "F.Cu" "F.Mask" "F.Paste")
			(net "GND")
		)
		(pad "BB72" smd oval
			(at 16.310102 4.99999 180)
			(size 0.254 0.3302)
			(layers "F.Cu" "F.Mask" "F.Paste")
			(net "GND")
		)
		(pad "BC2" smd circle
			(at -15.895066 5.500116 180)
			(size 0.3048 0.3048)
			(layers "F.Cu" "F.Mask" "F.Paste")
			(net "Net_479")
		)
		(pad "BC4" smd circle
			(at -15.064994 5.500116 180)
			(size 0.3048 0.3048)
			(layers "F.Cu" "F.Mask" "F.Paste")
			(net "FM_OC_DETECT_EN_N")
		)
		(pad "BC69" smd circle
			(at 15.064994 5.500116)
			(size 0.3048 0.3048)
			(layers "F.Cu" "F.Mask" "F.Paste")
			(net "GND")
		)
		(pad "BC71" smd circle
			(at 15.895066 5.500116)
			(size 0.3048 0.3048)
			(layers "F.Cu" "F.Mask" "F.Paste")
			(net "GND")
		)
		(pad "BD1" smd oval
			(at -16.310102 5.999988 180)
			(size 0.254 0.3302)
			(layers "F.Cu" "F.Mask" "F.Paste")
			(net "SMB_VR_STBY_LVC3_SDA_R1")
		)
		(pad "BD3" smd circle
			(at -15.48003 5.999988 180)
			(size 0.3048 0.3048)
			(layers "F.Cu" "F.Mask" "F.Paste")
			(net "FP_PWR_ID_LED_N")
		)
		(pad "BD5" smd circle
			(at -14.649958 5.999988 180)
			(size 0.3048 0.3048)
			(layers "F.Cu" "F.Mask" "F.Paste")
			(net "GND")
		)
		(pad "BD9" smd circle
			(at -12.8778 5.69595)
			(size 0.381 0.381)
			(layers "F.Cu" "F.Mask" "F.Paste")
			(net "FM_ADR_COMPLETE_R1")
		)
		(pad "BD13" smd circle
			(at -11.16076 5.69595)
			(size 0.381 0.381)
			(layers "F.Cu" "F.Mask" "F.Paste")
			(net "FM_BOARD_SKU_ID0")
		)
		(pad "BD17" smd circle
			(at -9.44372 5.69595)
			(size 0.381 0.381)
			(layers "F.Cu" "F.Mask" "F.Paste")
			(net "FM_BOARD_SKU_ID4")
		)
		(pad "BD20" smd circle
			(at -7.72668 5.69595)
			(size 0.381 0.381)
			(layers "F.Cu" "F.Mask" "F.Paste")
			(net "FM_CPU0_RC_EN")
		)
		(pad "BD24" smd circle
			(at -6.00964 5.69595)
			(size 0.381 0.381)
			(layers "F.Cu" "F.Mask" "F.Paste")
			(net "GND")
		)
		(pad "BD27" smd circle
			(at -4.2926 5.69595)
			(size 0.381 0.381)
			(layers "F.Cu" "F.Mask" "F.Paste")
			(net "GND")
		)
		(pad "BD31" smd circle
			(at -2.57556 5.69595)
			(size 0.381 0.381)
			(layers "F.Cu" "F.Mask" "F.Paste")
			(net "GND")
		)
		(pad "BD35" smd circle
			(at -0.85852 5.69595)
			(size 0.381 0.381)
			(layers "F.Cu" "F.Mask" "F.Paste")
			(net "GND")
		)
		(pad "BD38" smd circle
			(at 0.85852 5.69595)
			(size 0.381 0.381)
			(layers "F.Cu" "F.Mask" "F.Paste")
			(net "P1V05_PCH_STBY_KR_PLL")
		)
		(pad "BD42" smd circle
			(at 2.57556 5.69595)
			(size 0.381 0.381)
			(layers "F.Cu" "F.Mask" "F.Paste")
			(net "A_KR1_RBIAS")
		)
		(pad "BD46" smd circle
			(at 4.2926 5.69595)
			(size 0.381 0.381)
			(layers "F.Cu" "F.Mask" "F.Paste")
			(net "P1V8_PCH_STBY")
		)
		(pad "BD50" smd circle
			(at 6.00964 5.69595)
			(size 0.381 0.381)
			(layers "F.Cu" "F.Mask" "F.Paste")
			(net "GND")
		)
		(pad "BD54" smd circle
			(at 7.72668 5.69595)
			(size 0.381 0.381)
			(layers "F.Cu" "F.Mask" "F.Paste")
			(net "GND")
		)
		(pad "BD58" smd circle
			(at 9.44372 5.69595)
			(size 0.381 0.381)
			(layers "F.Cu" "F.Mask" "F.Paste")
			(net "A_PCIE_RCOMP_N")
		)
		(pad "BD61" smd circle
			(at 11.16076 5.69595)
			(size 0.381 0.381)
			(layers "F.Cu" "F.Mask" "F.Paste")
			(net "SATA6G_S0_RX_DP")
		)
		(pad "BD65" smd circle
			(at 12.8778 5.69595)
			(size 0.381 0.381)
			(layers "F.Cu" "F.Mask" "F.Paste")
			(net "Net_138")
		)
		(pad "BD68" smd circle
			(at 14.649958 5.999988)
			(size 0.3048 0.3048)
			(layers "F.Cu" "F.Mask" "F.Paste")
			(net "GND")
		)
		(pad "BD70" smd circle
			(at 15.48003 5.999988)
			(size 0.3048 0.3048)
			(layers "F.Cu" "F.Mask" "F.Paste")
			(net "TP_USB3_P06_RXP")
		)
		(pad "BD72" smd oval
			(at 16.310102 5.999988 180)
			(size 0.254 0.3302)
			(layers "F.Cu" "F.Mask" "F.Paste")
			(net "TP_USB3_P06_RXN")
		)
		(pad "BE2" smd circle
			(at -15.895066 6.500114 180)
			(size 0.3048 0.3048)
			(layers "F.Cu" "F.Mask" "F.Paste")
			(net "Net_457")
		)
		(pad "BE4" smd circle
			(at -15.064994 6.500114 180)
			(size 0.3048 0.3048)
			(layers "F.Cu" "F.Mask" "F.Paste")
			(net "SMB_LAN_STBY_LVC3_SDA_R1")
		)
		(pad "BE7" smd circle
			(at -13.73632 6.19125)
			(size 0.381 0.381)
			(layers "F.Cu" "F.Mask" "F.Paste")
			(net "FM_NMI_EVENT_N")
		)
		(pad "BE11" smd circle
			(at -12.01928 6.19125)
			(size 0.381 0.381)
			(layers "F.Cu" "F.Mask" "F.Paste")
			(net "Net_474")
		)
		(pad "BE15" smd circle
			(at -10.30224 6.19125)
			(size 0.381 0.381)
			(layers "F.Cu" "F.Mask" "F.Paste")
			(net "FM_BIOS_SMI_ACTIVE_N")
		)
		(pad "BE18" smd circle
			(at -8.5852 6.19125)
			(size 0.381 0.381)
			(layers "F.Cu" "F.Mask" "F.Paste")
			(net "FM_BOARD_SKU_ID3")
		)
		(pad "BE22" smd circle
			(at -6.86816 6.19125)
			(size 0.381 0.381)
			(layers "F.Cu" "F.Mask" "F.Paste")
			(net "Net_471")
		)
		(pad "BE26" smd circle
			(at -5.15112 6.19125)
			(size 0.381 0.381)
			(layers "F.Cu" "F.Mask" "F.Paste")
			(net "P3V3_STBY")
		)
		(pad "BE29" smd circle
			(at -3.43408 6.19125)
			(size 0.381 0.381)
			(layers "F.Cu" "F.Mask" "F.Paste")
			(net "GND")
		)
		(pad "BE33" smd circle
			(at -1.71704 6.19125)
			(size 0.381 0.381)
			(layers "F.Cu" "F.Mask" "F.Paste")
			(net "GND")
		)
		(pad "BE37" smd circle
			(at 0 6.19125)
			(size 0.381 0.381)
			(layers "F.Cu" "F.Mask" "F.Paste")
			(net "GND")
		)
		(pad "BE40" smd circle
			(at 1.71704 6.19125)
			(size 0.381 0.381)
			(layers "F.Cu" "F.Mask" "F.Paste")
			(net "P3V3_STBY")
		)
		(pad "BE44" smd circle
			(at 3.43408 6.19125)
			(size 0.381 0.381)
			(layers "F.Cu" "F.Mask" "F.Paste")
			(net "P3V3_STBY")
		)
		(pad "BE48" smd circle
			(at 5.15112 6.19125)
			(size 0.381 0.381)
			(layers "F.Cu" "F.Mask" "F.Paste")
			(net "P1V05_PCH_STBY")
		)
		(pad "BE52" smd circle
			(at 6.86816 6.19125)
			(size 0.381 0.381)
			(layers "F.Cu" "F.Mask" "F.Paste")
			(net "FM_CPLD_ADR_TRIGGER_R_N")
		)
		(pad "BE56" smd circle
			(at 8.5852 6.19125)
			(size 0.381 0.381)
			(layers "F.Cu" "F.Mask" "F.Paste")
			(net "GND")
		)
		(pad "BE59" smd circle
			(at 10.30224 6.19125)
			(size 0.381 0.381)
			(layers "F.Cu" "F.Mask" "F.Paste")
			(net "GND")
		)
		(pad "BE63" smd circle
			(at 12.01928 6.19125)
			(size 0.381 0.381)
			(layers "F.Cu" "F.Mask" "F.Paste")
			(net "GND")
		)
	)
)
